# BASEBOARD_FAB2 (Tioga Pass) — schematic netlist excerpt (pin names and nets, part order shuffled) for the footprints in the layout excerpt that follows; sources: Cadence DE-HDL packaged netlist, KiCad conversion of Wiwynn_Tioga_Pass_MB.brd

C8M5  CAP_A  47UF 4V 20% X5R  pkg 0603V  page 228 : A = PVDDQ_KLM ; B = GND
R7M7  RES  240 1.0% CHIP  pkg 0402  page 99 : A = PVCCIO_CPU1 ; B = SMB_DDR_KLM_SDA_G
R9R5  RES  49.9 1% CHIP  pkg 0402  page 167 : A = ISENSE_TMP421_2_E ; B = ISENSE_TMP421_2_DXP

(kicad_pcb
	(version 20260206)
	(generator "pcbnew")
	(generator_version "10.0")
	(general
		(thickness 1.6)
		(legacy_teardrops no)
	)
	(paper "A4")
	(title_block
		(title "Wiwynn_Tioga_Pass_MB.brd")
		(comment 1 "Tioga Pass / footprints 3944-3946 of 4770")
	)
	(layers
		(0 "F.Cu" signal "TOP")
		(4 "In1.Cu" signal "L2GND")
		(6 "In2.Cu" signal "L3")
		(8 "In3.Cu" signal "L4GND")
		(10 "In4.Cu" signal "L5")
		(12 "In5.Cu" signal "L6GND")
		(14 "In6.Cu" signal "L7VCC")
		(16 "In7.Cu" signal "L8VCC")
		(18 "In8.Cu" signal "L9GND")
		(20 "In9.Cu" signal "L10")
		(22 "In10.Cu" signal "L11GND")
		(24 "In11.Cu" signal "L12")
		(26 "In12.Cu" signal "L13GND")
		(2 "B.Cu" signal "BOTTOM")
		(9 "F.Adhes" user "F.Adhesive")
		(11 "B.Adhes" user "B.Adhesive")
		(13 "F.Paste" user "Package Geometry/Pastemask Top")
		(15 "B.Paste" user "Package Geometry/Pastemask Bottom")
		(5 "F.SilkS" user "Ref Des/Silkscreen Top")
		(7 "B.SilkS" user "Ref Des/Silkscreen Bottom")
		(1 "F.Mask" user "Board Geometry/Soldermask Top")
		(3 "B.Mask" user "Board Geometry/Soldermask Bottom")
		(17 "Dwgs.User" user "User.Drawings")
		(19 "Cmts.User" user "User.Comments")
		(21 "Eco1.User" user "User.Eco1")
		(23 "Eco2.User" user "User.Eco2")
		(25 "Edge.Cuts" user "Board Geometry/Outline")
		(27 "Margin" user)
		(31 "F.CrtYd" user "Package Geometry/Place Bound Top")
		(29 "B.CrtYd" user "Package Geometry/Place Bound Bottom")
		(35 "F.Fab" user "Ref Des/Assembly Top")
		(33 "B.Fab" user "Ref Des/Assembly Bottom")
	)
	(footprint ""
		(layer "B.Cu")
		(at 83.856068 -135.4074 -90)
		(property "Reference" "C8M5"
			(at -1.848866 0.752348 270)
			(unlocked yes)
			(layer "B.SilkS")
			(effects
				(font
					(size 1.27 0.9652)
					(thickness 0.1524)
				)
				(justify mirror)
			)
		)
		(property "Value" ""
			(at 0 0 90)
			(layer "B.Fab")
			(effects
				(font
					(size 1.27 1.27)
				)
				(justify mirror)
			)
		)
		(duplicate_pad_numbers_are_jumpers no)
		(fp_rect
			(start 0.500126 1.598422)
			(end -0.500126 -0.201422)
			(stroke
				(width 0)
				(type default)
			)
			(fill no)
			(layer "B.CrtYd")
		)
		(fp_line
			(start -0.500126 1.598422)
			(end 0.500126 1.598422)
			(stroke
				(width 0.1)
				(type default)
			)
			(layer "B.Fab")
		)
		(fp_line
			(start 0.500126 1.598422)
			(end 0.500126 -0.201422)
			(stroke
				(width 0.1)
				(type default)
			)
			(layer "B.Fab")
		)
		(fp_line
			(start -0.500126 -0.201422)
			(end -0.500126 1.598422)
			(stroke
				(width 0.1)
				(type default)
			)
			(layer "B.Fab")
		)
		(fp_line
			(start 0.500126 -0.201422)
			(end -0.500126 -0.201422)
			(stroke
				(width 0.1)
				(type default)
			)
			(layer "B.Fab")
		)
		(pad "1" smd rect
			(at 0 0 180)
			(size 0.889 0.9906)
			(layers "B.Cu" "B.Mask" "B.Paste")
			(net "PVDDQ_KLM")
		)
		(pad "2" smd rect
			(at 0 1.397 180)
			(size 0.889 0.9906)
			(layers "B.Cu" "B.Mask" "B.Paste")
			(net "GND")
		)
		(zone
			(layer "B.Cu")
			(hatch none 0.5)
			(connect_pads
				(clearance 0)
			)
			(min_thickness 0.25)
			(keepout
				(tracks not_allowed)
				(vias allowed)
				(pads allowed)
				(copperpour not_allowed)
				(footprints allowed)
			)
			(placement
				(enabled no)
				(sheetname "")
			)
			(fill
				(thermal_gap 0.5)
				(thermal_bridge_width 0.5)
				(island_removal_mode 0)
			)
			(polygon
				(pts
					(xy 82.903568 -134.9121) (xy 83.411568 -134.9121) (xy 83.411568 -135.9027) (xy 82.903568 -135.9027)
				)
			)
		)
		(zone
			(layer "B.Cu")
			(hatch none 0.5)
			(connect_pads
				(clearance 0)
			)
			(min_thickness 0.25)
			(keepout
				(tracks allowed)
				(vias not_allowed)
				(pads allowed)
				(copperpour not_allowed)
				(footprints allowed)
			)
			(placement
				(enabled no)
				(sheetname "")
			)
			(fill
				(thermal_gap 0.5)
				(thermal_bridge_width 0.5)
				(island_removal_mode 0)
			)
			(polygon
				(pts
					(xy 82.903568 -134.9121) (xy 83.411568 -134.9121) (xy 83.411568 -135.9027) (xy 82.903568 -135.9027)
				)
			)
		)
	)
	(footprint ""
		(layer "B.Cu")
		(at 17.907 -47.371 -90)
		(property "Reference" "R9R5"
			(at 0 0 90)
			(layer "B.SilkS")
			(hide yes)
			(effects
				(font
					(size 1.27 1.27)
				)
				(justify mirror)
			)
		)
		(property "Value" ""
			(at 0 0 90)
			(layer "B.Fab")
			(effects
				(font
					(size 1.27 1.27)
				)
				(justify mirror)
			)
		)
		(duplicate_pad_numbers_are_jumpers no)
		(fp_poly
			(pts
				(xy 0.2794 -0.1016) (xy -0.2794 -0.1016) (xy -0.2794 0.9906) (xy 0.2794 0.9906)
			)
			(stroke
				(width 0)
				(type default)
			)
			(fill no)
			(layer "B.CrtYd")
		)
		(fp_line
			(start -0.2794 0.9906)
			(end -0.2794 -0.1016)
			(stroke
				(width 0.1)
				(type default)
			)
			(layer "B.Fab")
		)
		(fp_line
			(start 0.2794 0.9906)
			(end -0.2794 0.9906)
			(stroke
				(width 0.1)
				(type default)
			)
			(layer "B.Fab")
		)
		(fp_line
			(start -0.2794 -0.1016)
			(end 0.2794 -0.1016)
			(stroke
				(width 0.1)
				(type default)
			)
			(layer "B.Fab")
		)
		(fp_line
			(start 0.2794 -0.1016)
			(end 0.2794 0.9906)
			(stroke
				(width 0.1)
				(type default)
			)
			(layer "B.Fab")
		)
		(pad "1" smd rect
			(at 0 0 90)
			(size 0.508 0.508)
			(layers "B.Cu" "B.Mask" "B.Paste")
			(net "ISENSE_TMP421_2_E")
		)
		(pad "2" smd rect
			(at 0 0.889 90)
			(size 0.508 0.508)
			(layers "B.Cu" "B.Mask" "B.Paste")
			(net "ISENSE_TMP421_2_DXP")
		)
		(zone
			(layer "B.Cu")
			(hatch none 0.5)
			(connect_pads
				(clearance 0)
			)
			(min_thickness 0.25)
			(keepout
				(tracks not_allowed)
				(vias allowed)
				(pads allowed)
				(copperpour not_allowed)
				(footprints allowed)
			)
			(placement
				(enabled no)
				(sheetname "")
			)
			(fill
				(thermal_gap 0.5)
				(thermal_bridge_width 0.5)
				(island_removal_mode 0)
			)
			(polygon
				(pts
					(xy 17.272 -47.117) (xy 17.272 -47.625) (xy 17.653 -47.625) (xy 17.653 -47.117)
				)
			)
		)
		(zone
			(layer "B.Cu")
			(hatch none 0.5)
			(connect_pads
				(clearance 0)
			)
			(min_thickness 0.25)
			(keepout
				(tracks allowed)
				(vias not_allowed)
				(pads allowed)
				(copperpour not_allowed)
				(footprints allowed)
			)
			(placement
				(enabled no)
				(sheetname "")
			)
			(fill
				(thermal_gap 0.5)
				(thermal_bridge_width 0.5)
				(island_removal_mode 0)
			)
			(polygon
				(pts
					(xy 17.653 -47.117) (xy 17.653 -47.625) (xy 17.272 -47.625) (xy 17.272 -47.117)
				)
			)
		)
	)
	(footprint ""
		(layer "B.Cu")
		(at 157.08122 -121.4247 180)
		(property "Reference" "R7M7"
			(at 0 0 0)
			(layer "B.SilkS")
			(hide yes)
			(effects
				(font
					(size 1.27 1.27)
				)
				(justify mirror)
			)
		)
		(property "Value" ""
			(at 0 0 0)
			(layer "B.Fab")
			(effects
				(font
					(size 1.27 1.27)
				)
				(justify mirror)
			)
		)
		(duplicate_pad_numbers_are_jumpers no)
		(fp_poly
			(pts
				(xy 0.2794 -0.1016) (xy -0.2794 -0.1016) (xy -0.2794 0.9906) (xy 0.2794 0.9906)
			)
			(stroke
				(width 0)
				(type default)
			)
			(fill no)
			(layer "B.CrtYd")
		)
		(fp_line
			(start 0.2794 0.9906)
			(end -0.2794 0.9906)
			(stroke
				(width 0.1)
				(type default)
			)
			(layer "B.Fab")
		)
		(fp_line
			(start 0.2794 -0.1016)
			(end 0.2794 0.9906)
			(stroke
				(width 0.1)
				(type default)
			)
			(layer "B.Fab")
		)
		(fp_line
			(start -0.2794 0.9906)
			(end -0.2794 -0.1016)
			(stroke
				(width 0.1)
				(type default)
			)
			(layer "B.Fab")
		)
		(fp_line
			(start -0.2794 -0.1016)
			(end 0.2794 -0.1016)
			(stroke
				(width 0.1)
				(type default)
			)
			(layer "B.Fab")
		)
		(pad "1" smd rect
			(at 0 0)
			(size 0.508 0.508)
			(layers "B.Cu" "B.Mask" "B.Paste")
			(net "PVCCIO_CPU1")
		)
		(pad "2" smd rect
			(at 0 0.889)
			(size 0.508 0.508)
			(layers "B.Cu" "B.Mask" "B.Paste")
			(net "SMB_DDR_KLM_SDA_G")
		)
		(zone
			(layer "B.Cu")
			(hatch none 0.5)
			(connect_pads
				(clearance 0)
			)
			(min_thickness 0.25)
			(keepout
				(tracks not_allowed)
				(vias allowed)
				(pads allowed)
				(copperpour not_allowed)
				(footprints allowed)
			)
			(placement
				(enabled no)
				(sheetname "")
			)
			(fill
				(thermal_gap 0.5)
				(thermal_bridge_width 0.5)
				(island_removal_mode 0)
			)
			(polygon
				(pts
					(xy 156.82722 -122.0597) (xy 157.33522 -122.0597) (xy 157.33522 -121.6787) (xy 156.82722 -121.6787)
				)
			)
		)
		(zone
			(layer "B.Cu")
			(hatch none 0.5)
			(connect_pads
				(clearance 0)
			)
			(min_thickness 0.25)
			(keepout
				(tracks allowed)
				(vias not_allowed)
				(pads allowed)
				(copperpour not_allowed)
				(footprints allowed)
			)
			(placement
				(enabled no)
				(sheetname "")
			)
			(fill
				(thermal_gap 0.5)
				(thermal_bridge_width 0.5)
				(island_removal_mode 0)
			)
			(polygon
				(pts
					(xy 156.82722 -121.6787) (xy 157.33522 -121.6787) (xy 157.33522 -122.0597) (xy 156.82722 -122.0597)
				)
			)
		)
	)
)
